(kicad_pcb
	(version 20260206)
	(generator "pcbnew")
	(generator_version "10.0")
	(general
		(thickness 1.6)
		(legacy_teardrops no)
	)
	(paper "A4")
	(title_block
		(title "v1-chassis-manager — T6M_CM_d_v01_1031_1645.brd")
		(comment 1 "Open CloudServer (Microsoft) / footprints 1633-1640 of 2512")
	)
	(layers
		(0 "F.Cu" signal "TOP")
		(4 "In1.Cu" signal "GND1")
		(6 "In2.Cu" signal "IN1")
		(8 "In3.Cu" signal "VCC1")
		(10 "In4.Cu" signal "VCC2")
		(12 "In5.Cu" signal "GND2")
		(14 "In6.Cu" signal "IN2")
		(16 "In7.Cu" signal "IN3")
		(18 "In8.Cu" signal "GND3")
		(2 "B.Cu" signal "BOTTOM")
		(9 "F.Adhes" user "F.Adhesive")
		(11 "B.Adhes" user "B.Adhesive")
		(13 "F.Paste" user "Package Geometry/Pastemask Top")
		(15 "B.Paste" user "Package Geometry/Pastemask Bottom")
		(5 "F.SilkS" user "Ref Des/Silkscreen Top")
		(7 "B.SilkS" user "Ref Des/Silkscreen Bottom")
		(1 "F.Mask" user "Board Geometry/Soldermask Top")
		(3 "B.Mask" user "Board Geometry/Soldermask Bottom")
		(17 "Dwgs.User" user "User.Drawings")
		(19 "Cmts.User" user "User.Comments")
		(21 "Eco1.User" user "User.Eco1")
		(23 "Eco2.User" user "User.Eco2")
		(25 "Edge.Cuts" user "Board Geometry/Outline")
		(27 "Margin" user)
		(31 "F.CrtYd" user "Package Geometry/Place Bound Top")
		(29 "B.CrtYd" user "Package Geometry/Place Bound Bottom")
		(35 "F.Fab" user "Ref Des/Assembly Top")
		(33 "B.Fab" user "Ref Des/Assembly Bottom")
	)
	(footprint ""
		(layer "B.Cu")
		(at 128.905 -55.245)
		(property "Reference" "U146"
			(at -1.70307 0.0254 270)
			(unlocked yes)
			(layer "B.SilkS")
			(effects
				(font
					(size 0.7874 0.5842)
					(thickness 0.1524)
				)
				(justify mirror)
			)
		)
		(property "Value" ""
			(at 0 0 0)
			(layer "B.Fab")
			(effects
				(font
					(size 1.27 1.27)
				)
				(justify mirror)
			)
		)
		(duplicate_pad_numbers_are_jumpers no)
		(fp_line
			(start -1.1176 -1.7018)
			(end -1.1176 1.7018)
			(stroke
				(width 0.1524)
				(type default)
			)
			(layer "B.SilkS")
		)
		(fp_line
			(start -1.1176 1.7018)
			(end 1.1176 1.7018)
			(stroke
				(width 0.1524)
				(type default)
			)
			(layer "B.SilkS")
		)
		(fp_line
			(start 0.7112 0)
			(end 1.1176 0.254)
			(stroke
				(width 0.1524)
				(type default)
			)
			(layer "B.SilkS")
		)
		(fp_line
			(start 1.1176 -1.7018)
			(end -1.1176 -1.7018)
			(stroke
				(width 0.1524)
				(type default)
			)
			(layer "B.SilkS")
		)
		(fp_line
			(start 1.1176 -1.7018)
			(end 1.1176 -0.254)
			(stroke
				(width 0.1524)
				(type default)
			)
			(layer "B.SilkS")
		)
		(fp_line
			(start 1.1176 -0.254)
			(end 0.7112 0)
			(stroke
				(width 0.1524)
				(type default)
			)
			(layer "B.SilkS")
		)
		(fp_line
			(start 1.1176 0.254)
			(end 1.1176 1.7018)
			(stroke
				(width 0.1524)
				(type default)
			)
			(layer "B.SilkS")
		)
		(fp_poly
			(pts
				(xy 0.675386 1.8161) (xy 0.446786 2.4003) (xy 0.878586 2.4003)
			)
			(stroke
				(width 0)
				(type default)
			)
			(fill yes)
			(layer "B.SilkS")
		)
		(fp_rect
			(start 1.1176 1.5494)
			(end -1.1176 -1.5494)
			(stroke
				(width 0)
				(type default)
			)
			(fill no)
			(layer "B.CrtYd")
		)
		(fp_line
			(start -1.1176 -1.5494)
			(end -1.1176 1.5494)
			(stroke
				(width 0.1)
				(type default)
			)
			(layer "B.Fab")
		)
		(fp_line
			(start -1.1176 1.5494)
			(end 1.1176 1.5494)
			(stroke
				(width 0.1)
				(type default)
			)
			(layer "B.Fab")
		)
		(fp_line
			(start 1.1176 -1.5494)
			(end -1.1176 -1.5494)
			(stroke
				(width 0.1)
				(type default)
			)
			(layer "B.Fab")
		)
		(fp_line
			(start 1.1176 -1.5494)
			(end 1.1176 -0.254)
			(stroke
				(width 0.1)
				(type default)
			)
			(layer "B.Fab")
		)
		(fp_line
			(start 1.1176 -0.254)
			(end 1.1176 0.254)
			(stroke
				(width 0.1)
				(type default)
			)
			(layer "B.Fab")
		)
		(fp_line
			(start 1.1176 0.254)
			(end 1.1176 1.5494)
			(stroke
				(width 0.1)
				(type default)
			)
			(layer "B.Fab")
		)
		(fp_poly
			(pts
				(xy 0.675386 1.8161) (xy 0.446786 2.4003) (xy 0.878586 2.4003)
			)
			(stroke
				(width 0)
				(type default)
			)
			(fill yes)
			(layer "B.Fab")
		)
		(pad "1" smd rect
			(at 0.649986 0.962406 180)
			(size 0.3302 1.1684)
			(layers "B.Cu" "B.Mask" "B.Paste")
			(net "Net_5")
		)
		(pad "2" smd rect
			(at 0 0.962406 180)
			(size 0.3302 1.1684)
			(layers "B.Cu" "B.Mask" "B.Paste")
			(net "UART_RI_P3_BUFFER_N")
		)
		(pad "3" smd rect
			(at -0.649986 0.962406 180)
			(size 0.3302 1.1684)
			(layers "B.Cu" "B.Mask" "B.Paste")
			(net "GND")
		)
		(pad "4" smd rect
			(at -0.649986 -0.962406 180)
			(size 0.3302 1.1684)
			(layers "B.Cu" "B.Mask" "B.Paste")
			(net "UART_RI_P3_N")
		)
		(pad "5" smd rect
			(at 0.649986 -0.962406 180)
			(size 0.3302 1.1684)
			(layers "B.Cu" "B.Mask" "B.Paste")
			(net "P3V3_NODE1")
		)
	)
	(footprint ""
		(layer "B.Cu")
		(at 57.852818 -85.025738 90)
		(property "Reference" "R100"
			(at 0.969772 -0.022352 270)
			(unlocked yes)
			(layer "B.SilkS")
			(effects
				(font
					(size 0.7874 0.5842)
					(thickness 0.1524)
				)
				(justify left mirror)
			)
		)
		(property "Value" ""
			(at 0 0 90)
			(layer "B.Fab")
			(effects
				(font
					(size 1.27 1.27)
				)
				(justify mirror)
			)
		)
		(duplicate_pad_numbers_are_jumpers no)
		(fp_line
			(start 0.7874 -0.4064)
			(end -0.7874 -0.4064)
			(stroke
				(width 0.1524)
				(type default)
			)
			(layer "B.SilkS")
		)
		(fp_line
			(start -0.7874 -0.4064)
			(end -0.7874 0.4064)
			(stroke
				(width 0.1524)
				(type default)
			)
			(layer "B.SilkS")
		)
		(fp_line
			(start 0.7874 0.4064)
			(end 0.7874 -0.4064)
			(stroke
				(width 0.1524)
				(type default)
			)
			(layer "B.SilkS")
		)
		(fp_line
			(start -0.7874 0.4064)
			(end 0.7874 0.4064)
			(stroke
				(width 0.1524)
				(type default)
			)
			(layer "B.SilkS")
		)
		(fp_poly
			(pts
				(xy 0.508 0.2794) (xy 0.508 0.2286) (xy 0.635 0.2286) (xy 0.635 -0.254) (xy 0.5334 -0.254) (xy 0.5334 -0.2794)
				(xy -0.5334 -0.2794) (xy -0.5334 -0.254) (xy -0.635 -0.254) (xy -0.635 0.254) (xy -0.5334 0.254)
				(xy -0.5334 0.2794)
			)
			(stroke
				(width 0)
				(type default)
			)
			(fill no)
			(layer "B.CrtYd")
		)
		(pad "1" smd rect
			(at -0.40005 0 270)
			(size 0.4572 0.508)
			(layers "B.Cu" "B.Mask" "B.Paste")
			(net "A_CPU_NODE1_MV_GPIO_RCOMP")
		)
		(pad "2" smd rect
			(at 0.40005 0 270)
			(size 0.4572 0.508)
			(layers "B.Cu" "B.Mask" "B.Paste")
			(net "GND")
		)
	)
	(footprint ""
		(layer "B.Cu")
		(at 133.9596 -55.6006 -90)
		(property "Reference" "U145"
			(at -1.75133 0.254 0)
			(unlocked yes)
			(layer "B.SilkS")
			(effects
				(font
					(size 0.7874 0.5842)
					(thickness 0.1524)
				)
				(justify mirror)
			)
		)
		(property "Value" ""
			(at 0 0 90)
			(layer "B.Fab")
			(effects
				(font
					(size 1.27 1.27)
				)
				(justify mirror)
			)
		)
		(duplicate_pad_numbers_are_jumpers no)
		(fp_line
			(start -1.1176 1.7018)
			(end 1.1176 1.7018)
			(stroke
				(width 0.1524)
				(type default)
			)
			(layer "B.SilkS")
		)
		(fp_line
			(start 1.1176 0.254)
			(end 1.1176 1.7018)
			(stroke
				(width 0.1524)
				(type default)
			)
			(layer "B.SilkS")
		)
		(fp_line
			(start 0.7112 0)
			(end 1.1176 0.254)
			(stroke
				(width 0.1524)
				(type default)
			)
			(layer "B.SilkS")
		)
		(fp_line
			(start 1.1176 -0.254)
			(end 0.7112 0)
			(stroke
				(width 0.1524)
				(type default)
			)
			(layer "B.SilkS")
		)
		(fp_line
			(start -1.1176 -1.7018)
			(end -1.1176 1.7018)
			(stroke
				(width 0.1524)
				(type default)
			)
			(layer "B.SilkS")
		)
		(fp_line
			(start 1.1176 -1.7018)
			(end 1.1176 -0.254)
			(stroke
				(width 0.1524)
				(type default)
			)
			(layer "B.SilkS")
		)
		(fp_line
			(start 1.1176 -1.7018)
			(end -1.1176 -1.7018)
			(stroke
				(width 0.1524)
				(type default)
			)
			(layer "B.SilkS")
		)
		(fp_poly
			(pts
				(xy 0.675386 1.8161) (xy 0.446786 2.4003) (xy 0.878586 2.4003)
			)
			(stroke
				(width 0)
				(type default)
			)
			(fill yes)
			(layer "B.SilkS")
		)
		(fp_rect
			(start 1.1176 1.5494)
			(end -1.1176 -1.5494)
			(stroke
				(width 0)
				(type default)
			)
			(fill no)
			(layer "B.CrtYd")
		)
		(fp_line
			(start -1.1176 1.5494)
			(end 1.1176 1.5494)
			(stroke
				(width 0.1)
				(type default)
			)
			(layer "B.Fab")
		)
		(fp_line
			(start 1.1176 0.254)
			(end 1.1176 1.5494)
			(stroke
				(width 0.1)
				(type default)
			)
			(layer "B.Fab")
		)
		(fp_line
			(start 1.1176 -0.254)
			(end 1.1176 0.254)
			(stroke
				(width 0.1)
				(type default)
			)
			(layer "B.Fab")
		)
		(fp_line
			(start -1.1176 -1.5494)
			(end -1.1176 1.5494)
			(stroke
				(width 0.1)
				(type default)
			)
			(layer "B.Fab")
		)
		(fp_line
			(start 1.1176 -1.5494)
			(end 1.1176 -0.254)
			(stroke
				(width 0.1)
				(type default)
			)
			(layer "B.Fab")
		)
		(fp_line
			(start 1.1176 -1.5494)
			(end -1.1176 -1.5494)
			(stroke
				(width 0.1)
				(type default)
			)
			(layer "B.Fab")
		)
		(fp_poly
			(pts
				(xy 0.675386 1.8161) (xy 0.446786 2.4003) (xy 0.878586 2.4003)
			)
			(stroke
				(width 0)
				(type default)
			)
			(fill yes)
			(layer "B.Fab")
		)
		(pad "1" smd rect
			(at 0.649986 0.962406 90)
			(size 0.3302 1.1684)
			(layers "B.Cu" "B.Mask" "B.Paste")
			(net "Net_6")
		)
		(pad "2" smd rect
			(at 0 0.962406 90)
			(size 0.3302 1.1684)
			(layers "B.Cu" "B.Mask" "B.Paste")
			(net "UART_RI_P4_N")
		)
		(pad "3" smd rect
			(at -0.649986 0.962406 90)
			(size 0.3302 1.1684)
			(layers "B.Cu" "B.Mask" "B.Paste")
			(net "GND")
		)
		(pad "4" smd rect
			(at -0.649986 -0.962406 90)
			(size 0.3302 1.1684)
			(layers "B.Cu" "B.Mask" "B.Paste")
			(net "UART_RI_P4_R_N")
		)
		(pad "5" smd rect
			(at 0.649986 -0.962406 90)
			(size 0.3302 1.1684)
			(layers "B.Cu" "B.Mask" "B.Paste")
			(net "P3V3_NODE1")
		)
	)
	(footprint ""
		(layer "B.Cu")
		(at 164.804852 -104.84739 90)
		(property "Reference" "C381"
			(at 1.423416 6.517386 270)
			(unlocked yes)
			(layer "B.SilkS")
			(effects
				(font
					(size 0.7874 0.5842)
					(thickness 0.1524)
				)
				(justify left mirror)
			)
		)
		(property "Value" ""
			(at 0 0 90)
			(layer "B.Fab")
			(effects
				(font
					(size 1.27 1.27)
				)
				(justify mirror)
			)
		)
		(duplicate_pad_numbers_are_jumpers no)
		(fp_line
			(start 0.7874 -0.4064)
			(end -0.7874 -0.4064)
			(stroke
				(width 0.1524)
				(type default)
			)
			(layer "B.SilkS")
		)
		(fp_line
			(start -0.7874 -0.4064)
			(end -0.7874 0.4064)
			(stroke
				(width 0.1524)
				(type default)
			)
			(layer "B.SilkS")
		)
		(fp_line
			(start 0 0.381)
			(end 0 -0.381)
			(stroke
				(width 0.1524)
				(type default)
			)
			(layer "B.SilkS")
		)
		(fp_line
			(start 0.7874 0.4064)
			(end 0.7874 -0.4064)
			(stroke
				(width 0.1524)
				(type default)
			)
			(layer "B.SilkS")
		)
		(fp_line
			(start -0.7874 0.4064)
			(end 0.7874 0.4064)
			(stroke
				(width 0.1524)
				(type default)
			)
			(layer "B.SilkS")
		)
		(fp_poly
			(pts
				(xy 0.5334 0.254) (xy 0.635 0.254) (xy 0.635 0.2286) (xy 0.635 -0.254) (xy 0.5334 -0.254) (xy 0.5334 -0.2794)
				(xy -0.5334 -0.2794) (xy -0.5334 -0.254) (xy -0.635 -0.254) (xy -0.635 0.254) (xy -0.5334 0.254)
				(xy -0.5334 0.2794) (xy 0.508 0.2794) (xy 0.5334 0.2794)
			)
			(stroke
				(width 0)
				(type default)
			)
			(fill no)
			(layer "B.CrtYd")
		)
		(pad "1" smd rect
			(at -0.40005 0 270)
			(size 0.4572 0.508)
			(layers "B.Cu" "B.Mask" "B.Paste")
			(net "GND")
		)
		(pad "2" smd rect
			(at 0.40005 0 270)
			(size 0.4572 0.508)
			(layers "B.Cu" "B.Mask" "B.Paste")
			(net "P3V3_NODE1")
		)
	)
	(footprint ""
		(layer "B.Cu")
		(at 59.102498 -96.315784 -90)
		(property "Reference" "R60"
			(at -6.3627 5.414264 270)
			(unlocked yes)
			(layer "B.SilkS")
			(effects
				(font
					(size 0.7874 0.5842)
					(thickness 0.1524)
				)
				(justify left mirror)
			)
		)
		(property "Value" ""
			(at 0 0 90)
			(layer "B.Fab")
			(effects
				(font
					(size 1.27 1.27)
				)
				(justify mirror)
			)
		)
		(duplicate_pad_numbers_are_jumpers no)
		(fp_line
			(start -0.7874 0.4064)
			(end 0.7874 0.4064)
			(stroke
				(width 0.1524)
				(type default)
			)
			(layer "B.SilkS")
		)
		(fp_line
			(start 0.7874 0.4064)
			(end 0.7874 -0.4064)
			(stroke
				(width 0.1524)
				(type default)
			)
			(layer "B.SilkS")
		)
		(fp_line
			(start -0.7874 -0.4064)
			(end -0.7874 0.4064)
			(stroke
				(width 0.1524)
				(type default)
			)
			(layer "B.SilkS")
		)
		(fp_line
			(start 0.7874 -0.4064)
			(end -0.7874 -0.4064)
			(stroke
				(width 0.1524)
				(type default)
			)
			(layer "B.SilkS")
		)
		(fp_poly
			(pts
				(xy 0.508 0.2794) (xy 0.508 0.2286) (xy 0.635 0.2286) (xy 0.635 -0.254) (xy 0.5334 -0.254) (xy 0.5334 -0.2794)
				(xy -0.5334 -0.2794) (xy -0.5334 -0.254) (xy -0.635 -0.254) (xy -0.635 0.254) (xy -0.5334 0.254)
				(xy -0.5334 0.2794)
			)
			(stroke
				(width 0)
				(type default)
			)
			(fill no)
			(layer "B.CrtYd")
		)
		(pad "1" smd rect
			(at -0.40005 0 90)
			(size 0.4572 0.508)
			(layers "B.Cu" "B.Mask" "B.Paste")
			(net "LPC_CPU_NODE1_LAD3")
		)
		(pad "2" smd rect
			(at 0.40005 0 90)
			(size 0.4572 0.508)
			(layers "B.Cu" "B.Mask" "B.Paste")
			(net "LPC_CPU_NODE1_LAD3_R")
		)
	)
	(footprint ""
		(layer "B.Cu")
		(at 131.3053 -40.62476 180)
		(property "Reference" "R1079"
			(at -0.4699 1.89357 0)
			(unlocked yes)
			(layer "B.SilkS")
			(effects
				(font
					(size 0.7874 0.5842)
					(thickness 0.1524)
				)
				(justify left mirror)
			)
		)
		(property "Value" ""
			(at 0 0 0)
			(layer "B.Fab")
			(effects
				(font
					(size 1.27 1.27)
				)
				(justify mirror)
			)
		)
		(duplicate_pad_numbers_are_jumpers no)
		(fp_line
			(start 0.7874 0.4064)
			(end 0.7874 -0.4064)
			(stroke
				(width 0.1524)
				(type default)
			)
			(layer "B.SilkS")
		)
		(fp_line
			(start 0.7874 -0.4064)
			(end -0.7874 -0.4064)
			(stroke
				(width 0.1524)
				(type default)
			)
			(layer "B.SilkS")
		)
		(fp_line
			(start -0.7874 0.4064)
			(end 0.7874 0.4064)
			(stroke
				(width 0.1524)
				(type default)
			)
			(layer "B.SilkS")
		)
		(fp_line
			(start -0.7874 -0.4064)
			(end -0.7874 0.4064)
			(stroke
				(width 0.1524)
				(type default)
			)
			(layer "B.SilkS")
		)
		(fp_poly
			(pts
				(xy 0.508 0.2794) (xy 0.508 0.2286) (xy 0.635 0.2286) (xy 0.635 -0.254) (xy 0.5334 -0.254) (xy 0.5334 -0.2794)
				(xy -0.5334 -0.2794) (xy -0.5334 -0.254) (xy -0.635 -0.254) (xy -0.635 0.254) (xy -0.5334 0.254)
				(xy -0.5334 0.2794)
			)
			(stroke
				(width 0)
				(type default)
			)
			(fill no)
			(layer "B.CrtYd")
		)
		(pad "1" smd rect
			(at -0.40005 0)
			(size 0.4572 0.508)
			(layers "B.Cu" "B.Mask" "B.Paste")
			(net "SIO_JTAG_CPLD2_TMS")
		)
		(pad "2" smd rect
			(at 0.40005 0)
			(size 0.4572 0.508)
			(layers "B.Cu" "B.Mask" "B.Paste")
			(net "JTAG_CPLD2_TMS")
		)
	)
	(footprint ""
		(layer "B.Cu")
		(at 135.577072 -46.950376 90)
		(property "Reference" "R1137"
			(at 3.113024 11.233658 270)
			(unlocked yes)
			(layer "B.SilkS")
			(effects
				(font
					(size 0.7874 0.5842)
					(thickness 0.1524)
				)
				(justify left mirror)
			)
		)
		(property "Value" ""
			(at 0 0 90)
			(layer "B.Fab")
			(effects
				(font
					(size 1.27 1.27)
				)
				(justify mirror)
			)
		)
		(duplicate_pad_numbers_are_jumpers no)
		(fp_line
			(start 0.7874 -0.4064)
			(end -0.7874 -0.4064)
			(stroke
				(width 0.1524)
				(type default)
			)
			(layer "B.SilkS")
		)
		(fp_line
			(start -0.7874 -0.4064)
			(end -0.7874 0.4064)
			(stroke
				(width 0.1524)
				(type default)
			)
			(layer "B.SilkS")
		)
		(fp_line
			(start 0.7874 0.4064)
			(end 0.7874 -0.4064)
			(stroke
				(width 0.1524)
				(type default)
			)
			(layer "B.SilkS")
		)
		(fp_line
			(start -0.7874 0.4064)
			(end 0.7874 0.4064)
			(stroke
				(width 0.1524)
				(type default)
			)
			(layer "B.SilkS")
		)
		(fp_poly
			(pts
				(xy 0.508 0.2794) (xy 0.508 0.2286) (xy 0.635 0.2286) (xy 0.635 -0.254) (xy 0.5334 -0.254) (xy 0.5334 -0.2794)
				(xy -0.5334 -0.2794) (xy -0.5334 -0.254) (xy -0.635 -0.254) (xy -0.635 0.254) (xy -0.5334 0.254)
				(xy -0.5334 0.2794)
			)
			(stroke
				(width 0)
				(type default)
			)
			(fill no)
			(layer "B.CrtYd")
		)
		(pad "1" smd rect
			(at -0.40005 0 270)
			(size 0.4572 0.508)
			(layers "B.Cu" "B.Mask" "B.Paste")
			(net "GND")
		)
		(pad "2" smd rect
			(at 0.40005 0 270)
			(size 0.4572 0.508)
			(layers "B.Cu" "B.Mask" "B.Paste")
			(net "UART_RTS_P3_R_N")
		)
	)
	(footprint ""
		(layer "B.Cu")
		(at 164.592 -188.087 -90)
		(property "Reference" "R1333"
			(at 2.0066 1.60147 270)
			(unlocked yes)
			(layer "B.SilkS")
			(effects
				(font
					(size 0.7874 0.5842)
					(thickness 0.1524)
				)
				(justify left mirror)
			)
		)
		(property "Value" ""
			(at 0 0 90)
			(layer "B.Fab")
			(effects
				(font
					(size 1.27 1.27)
				)
				(justify mirror)
			)
		)
		(duplicate_pad_numbers_are_jumpers no)
		(fp_line
			(start -0.7874 0.4064)
			(end 0.7874 0.4064)
			(stroke
				(width 0.1524)
				(type default)
			)
			(layer "B.SilkS")
		)
		(fp_line
			(start 0.7874 0.4064)
			(end 0.7874 -0.4064)
			(stroke
				(width 0.1524)
				(type default)
			)
			(layer "B.SilkS")
		)
		(fp_line
			(start -0.7874 -0.4064)
			(end -0.7874 0.4064)
			(stroke
				(width 0.1524)
				(type default)
			)
			(layer "B.SilkS")
		)
		(fp_line
			(start 0.7874 -0.4064)
			(end -0.7874 -0.4064)
			(stroke
				(width 0.1524)
				(type default)
			)
			(layer "B.SilkS")
		)
		(fp_poly
			(pts
				(xy 0.508 0.2794) (xy 0.508 0.2286) (xy 0.635 0.2286) (xy 0.635 -0.254) (xy 0.5334 -0.254) (xy 0.5334 -0.2794)
				(xy -0.5334 -0.2794) (xy -0.5334 -0.254) (xy -0.635 -0.254) (xy -0.635 0.254) (xy -0.5334 0.254)
				(xy -0.5334 0.2794)
			)
			(stroke
				(width 0)
				(type default)
			)
			(fill no)
			(layer "B.CrtYd")
		)
		(pad "1" smd rect
			(at -0.40005 0 90)
			(size 0.4572 0.508)
			(layers "B.Cu" "B.Mask" "B.Paste")
			(net "UART_RI_RP6_L_N_R")
		)
		(pad "2" smd rect
			(at 0.40005 0 90)
			(size 0.4572 0.508)
			(layers "B.Cu" "B.Mask" "B.Paste")
			(net "UART_RI_RP6_L_N")
		)
	)
)
